FILE_TYPE = MACRO_DRAWING;
SET COLOR_WIRE YELLOW;
SET COLOR_PROP ORANGE;
SET COLOR_DOT WHITE;
SET COLOR_ARC YELLOW;
SET COLOR_BODY GREEN;
SET COLOR_NOTE PURPLE;
SET PROP_DISPLAY VALUE;
SET PAGE_NUMBER P126;
FORCEADD QUANTA_TITLE_BLOCK_C..1
(0 0);
FORCEPROP 1 LAST CUSTOM_TXT_CDS <NAME_2>
J 0
(-3175 50);
FORCEPROP 1 LAST CUSTOM_TXT_CDS <NAME_1>
J 0
(-3175 175);
FORCEPROP 1 LAST CUSTOM_TXT_CDS <Q_NUMBER>
J 0
(-1403 103);
DISPLAY 1.212766 (-1403 103);
FORCEPROP 1 LAST CUSTOM_TXT_CDS <Q_PROJ>
J 0
(-2382 102);
DISPLAY 1.212766 (-2382 102);
FORCEPROP 1 LAST CUSTOM_TXT_CDS <Q_REV>
J 0
(-184 103);
DISPLAY 1.212766 (-184 103);
FORCEPROP 1 LAST CUSTOM_TXT_CDS <CON_LAST_MODIFIED>
J 0
(-1885 15);
DISPLAY 0.978723 (-1885 15);
FORCEPROP 1 LAST CUSTOM_TXT_CDS <CON_PAGE_NUM> OF <CON_TOTAL_PAGES>
J 0
(-446 18);
DISPLAY 0.978723 (-446 18);
FORCEPROP 1 LAST Q_TITLE E1.S CONN3
J 0
(-9275 50);
DISPLAY 2.446809 (-9275 50);
PAINT GREEN (-9275 50);
FORCEPROP 1 LAST Q_DEPT BU9
J 1
(-3763 49);
DISPLAY 1.957447 (-3763 49);
PAINT GREEN (-3763 49);
FORCEPROP 2 LAST PAGE_BORDER TRUE
J 0
(-7890 5250);
DISPLAY 0.638298 (-7890 5250);
PAINT PINK (-7890 5250);
DISPLAY INVISIBLE (-7890 5250);
FORCEPROP 2 LAST CDS_LIB pure_quanta
J 0
(0 0);
DISPLAY INVISIBLE (0 0);
FORCEPROP 1 LAST CDS_LMAN_SYM_OUTLINE -9475,6775,100,-125
J 0
(0 0);
DISPLAY 0.468085 (0 0);
PAINT GREEN (0 0);
DISPLAY INVISIBLE (0 0);
FORCEPROP 1 LAST COMMENT_BODY TRUE
J 0
(12 -13);
DISPLAY 0.978723 (12 -13);
PAINT GREEN (12 -13);
DISPLAY INVISIBLE (12 -13);
FORCEPROP 2 LAST CDS_XR_PAGE_TITLE CR-126 : @T6G_MB_LIB.T6G(SCH_1):PAGE126
J 0
(-7890 5250);
DISPLAY 0.638298 (-7890 5250);
PAINT PINK (-7890 5250);
DISPLAY INVISIBLE (-7890 5250);
FORCEPROP 2 LAST CUSTOM_TXT_CDS <XR_PAGE_TITLE>
J 0
(-7890 5250);
DISPLAY 0.638298 (-7890 5250);
PAINT PINK (-7890 5250);
DISPLAY INVISIBLE (-7890 5250);
FORCEPROP 0 LAST CDS_CON_LAST_MODIFIED Wed Mar 09 18:12:35 2022
J 0
(-1885 15);
DISPLAY INVISIBLE (-1885 15);
QUIT
